(kicad_pcb
	(version 20260206)
	(generator "pcbnew")
	(generator_version "10.0")
	(general
		(thickness 1.6)
		(legacy_teardrops no)
	)
	(paper "A4")
	(title_block
		(title "peb — Lightning_PEB_BRD.brd")
		(comment 1 "Lightning (Wiwynn / Facebook NVMe JBOF) / footprints 586-592 of 2563")
	)
	(layers
		(0 "F.Cu" signal "TOP")
		(4 "In1.Cu" signal "L2GND")
		(6 "In2.Cu" signal "L3")
		(8 "In3.Cu" signal "L4VCC")
		(10 "In4.Cu" signal "L5VCC")
		(12 "In5.Cu" signal "L6")
		(14 "In6.Cu" signal "L7GND")
		(2 "B.Cu" signal "BOTTOM")
		(9 "F.Adhes" user "F.Adhesive")
		(11 "B.Adhes" user "B.Adhesive")
		(13 "F.Paste" user "Package Geometry/Pastemask Top")
		(15 "B.Paste" user "Package Geometry/Pastemask Bottom")
		(5 "F.SilkS" user "Ref Des/Silkscreen Top")
		(7 "B.SilkS" user "Ref Des/Silkscreen Bottom")
		(1 "F.Mask" user "Board Geometry/Soldermask Top")
		(3 "B.Mask" user "Board Geometry/Soldermask Bottom")
		(17 "Dwgs.User" user "User.Drawings")
		(19 "Cmts.User" user "User.Comments")
		(21 "Eco1.User" user "User.Eco1")
		(23 "Eco2.User" user "User.Eco2")
		(25 "Edge.Cuts" user "Board Geometry/Outline")
		(27 "Margin" user)
		(31 "F.CrtYd" user "Package Geometry/Place Bound Top")
		(29 "B.CrtYd" user "Package Geometry/Place Bound Bottom")
		(35 "F.Fab" user "Ref Des/Assembly Top")
		(33 "B.Fab" user "Ref Des/Assembly Bottom")
	)
	(footprint ""
		(layer "F.Cu")
		(at 10.760964 -95.073978)
		(property "Reference" "U21"
			(at 0 0 0)
			(layer "F.SilkS")
			(hide yes)
			(effects
				(font
					(size 1.27 1.27)
				)
			)
		)
		(property "Value" "ICS551MLFT-GP"
			(at -3.707384 -1.5367 0)
			(unlocked yes)
			(layer "F.Fab")
			(hide yes)
			(effects
				(font
					(size 1.016 1.016)
					(thickness 0.1524)
				)
			)
		)
		(property "Device Type" "SOIC8H69"
			(at -3.707384 -3.0607 0)
			(unlocked yes)
			(layer "F.Fab")
			(hide yes)
			(effects
				(font
					(size 1.016 1.016)
					(thickness 0.1524)
				)
			)
		)
		(duplicate_pad_numbers_are_jumpers no)
		(fp_line
			(start -2.7432 -1.4224)
			(end -2.7432 1.4224)
			(stroke
				(width 0.1524)
				(type default)
			)
			(layer "F.SilkS")
		)
		(fp_line
			(start -2.7432 1.4224)
			(end -2.6416 1.4224)
			(stroke
				(width 0.1524)
				(type default)
			)
			(layer "F.SilkS")
		)
		(fp_line
			(start -2.7432 1.4224)
			(end 2.1336 1.4224)
			(stroke
				(width 0.1524)
				(type default)
			)
			(layer "F.SilkS")
		)
		(fp_line
			(start -2.7178 -0.508)
			(end -2.1844 -0.0508)
			(stroke
				(width 0.1524)
				(type default)
			)
			(layer "F.SilkS")
		)
		(fp_line
			(start -2.6289 3.4417)
			(end -2.6289 1.4732)
			(stroke
				(width 0.381)
				(type default)
			)
			(layer "F.SilkS")
		)
		(fp_line
			(start -2.1844 -0.0508)
			(end -2.7178 0.508)
			(stroke
				(width 0.1524)
				(type default)
			)
			(layer "F.SilkS")
		)
		(fp_line
			(start 2.1336 -1.4224)
			(end -2.7432 -1.4224)
			(stroke
				(width 0.1524)
				(type default)
			)
			(layer "F.SilkS")
		)
		(fp_line
			(start 2.1336 1.4224)
			(end 2.1336 -1.4224)
			(stroke
				(width 0.1524)
				(type default)
			)
			(layer "F.SilkS")
		)
		(fp_poly
			(pts
				(xy -2.2098 -1.4224) (xy -2.2098 1.4224) (xy 2.2098 1.4224) (xy 2.2098 -1.4224)
			)
			(stroke
				(width 0)
				(type default)
			)
			(fill yes)
			(layer "F.SilkS")
		)
		(fp_rect
			(start -2.450084 2.999994)
			(end 2.450084 -2.999994)
			(stroke
				(width 0)
				(type default)
			)
			(fill no)
			(layer "F.CrtYd")
		)
		(fp_poly
			(pts
				(xy -2.8194 3.6322) (xy -2.8194 -3.6322) (xy 2.8194 -3.6322) (xy 2.8194 1.18364) (xy 2.450084 1.18364)
				(xy 2.450084 -2.999994) (xy -2.450084 -2.999994) (xy -2.450084 2.999994) (xy 2.450084 2.999994)
				(xy 2.450084 1.18618) (xy 2.8194 1.18618) (xy 2.8194 3.6322)
			)
			(stroke
				(width 0)
				(type default)
			)
			(fill no)
			(layer "F.CrtYd")
		)
		(fp_rect
			(start -2.8194 3.6322)
			(end 2.8194 -3.6322)
			(stroke
				(width 0)
				(type default)
			)
			(fill no)
			(layer "F.Fab")
		)
		(pad "1" smd rect
			(at -1.905 2.54)
			(size 0.635 1.651)
			(layers "F.Cu" "F.Mask" "F.Paste")
			(net "50M_CLK_OUT_R")
		)
		(pad "2" smd rect
			(at -0.635 2.54)
			(size 0.635 1.651)
			(layers "F.Cu" "F.Mask" "F.Paste")
			(net "CLK_50M_BMC_NCSI")
		)
		(pad "3" smd rect
			(at 0.635 2.54)
			(size 0.635 1.651)
			(layers "F.Cu" "F.Mask" "F.Paste")
			(net "CLK_50M_RMII_PHY")
		)
		(pad "4" smd rect
			(at 1.905 2.54)
			(size 0.635 1.651)
			(layers "F.Cu" "F.Mask" "F.Paste")
			(net "NCSI_10G_RCLK")
		)
		(pad "5" smd rect
			(at 1.905 -2.54)
			(size 0.635 1.651)
			(layers "F.Cu" "F.Mask" "F.Paste")
			(net "CLK_50M_BMC0")
		)
		(pad "6" smd rect
			(at 0.635 -2.54)
			(size 0.635 1.651)
			(layers "F.Cu" "F.Mask" "F.Paste")
			(net "GND")
		)
		(pad "7" smd rect
			(at -0.635 -2.54)
			(size 0.635 1.651)
			(layers "F.Cu" "F.Mask" "F.Paste")
			(net "P3V3_STBY")
		)
		(pad "8" smd rect
			(at -1.905 -2.54)
			(size 0.635 1.651)
			(layers "F.Cu" "F.Mask" "F.Paste")
			(net "50M_CLK_OE")
		)
	)
	(footprint ""
		(layer "F.Cu")
		(at 172.792136 -212.420454 180)
		(property "Reference" "C138"
			(at 0 0 180)
			(layer "F.SilkS")
			(hide yes)
			(effects
				(font
					(size 1.27 1.27)
				)
			)
		)
		(property "Value" "SCD22U10V2KX-1GP"
			(at 1.1811 -2.7051 180)
			(unlocked yes)
			(layer "F.Fab")
			(hide yes)
			(effects
				(font
					(size 1.016 1.016)
					(thickness 0.1524)
				)
			)
		)
		(property "Device Type" "C402H22"
			(at 1.1811 -4.2291 180)
			(unlocked yes)
			(layer "F.Fab")
			(hide yes)
			(effects
				(font
					(size 1.016 1.016)
					(thickness 0.1524)
				)
			)
		)
		(duplicate_pad_numbers_are_jumpers no)
		(fp_rect
			(start -0.4318 0.9525)
			(end 0.4318 -0.9525)
			(stroke
				(width 0)
				(type default)
			)
			(fill no)
			(layer "F.CrtYd")
		)
		(fp_rect
			(start -0.4318 0.9525)
			(end 0.4318 -0.9525)
			(stroke
				(width 0)
				(type default)
			)
			(fill no)
			(layer "F.Fab")
		)
		(pad "1" smd custom
			(at 0 -0.4445 180)
			(size 0.1524 0.1524)
			(layers "F.Cu" "F.Mask" "F.Paste")
			(net "PCIE_TX_CAP_P49")
			(options
				(clearance outline)
				(anchor circle)
			)
			(primitives
				(gr_poly
					(pts
						(arc
							(start 0.3048 -0.2032)
							(mid 0.275042 -0.275042)
							(end 0.2032 -0.3048)
						)
						(arc
							(start -0.2032 -0.3048)
							(mid -0.275042 -0.275042)
							(end -0.3048 -0.2032)
						)
						(arc
							(start -0.3048 0.2032)
							(mid -0.275042 0.275042)
							(end -0.2032 0.3048)
						)
						(arc
							(start 0.2032 0.3048)
							(mid 0.275042 0.275042)
							(end 0.3048 0.2032)
						)
					)
					(width 0)
					(fill yes)
				)
			)
		)
		(pad "2" smd custom
			(at 0 0.4445 180)
			(size 0.1524 0.1524)
			(layers "F.Cu" "F.Mask" "F.Paste")
			(net "PCIE_TX_P49")
			(options
				(clearance outline)
				(anchor circle)
			)
			(primitives
				(gr_poly
					(pts
						(arc
							(start 0.3048 -0.2032)
							(mid 0.275042 -0.275042)
							(end 0.2032 -0.3048)
						)
						(arc
							(start -0.2032 -0.3048)
							(mid -0.275042 -0.275042)
							(end -0.3048 -0.2032)
						)
						(arc
							(start -0.3048 0.2032)
							(mid -0.275042 0.275042)
							(end -0.2032 0.3048)
						)
						(arc
							(start 0.2032 0.3048)
							(mid 0.275042 0.275042)
							(end 0.3048 0.2032)
						)
					)
					(width 0)
					(fill yes)
				)
			)
		)
	)
	(footprint ""
		(layer "F.Cu")
		(at 160.366202 -58.447432)
		(property "Reference" "PR167"
			(at 0 0 0)
			(layer "F.SilkS")
			(hide yes)
			(effects
				(font
					(size 1.27 1.27)
				)
			)
		)
		(property "Value" "0R2J-2-GP"
			(at 0.064008 -3.993896 0)
			(unlocked yes)
			(layer "F.Fab")
			(hide yes)
			(effects
				(font
					(size 1.016 1.016)
					(thickness 0.1524)
				)
			)
		)
		(property "Device Type" "R402H16"
			(at 0.064008 -5.517896 0)
			(unlocked yes)
			(layer "F.Fab")
			(hide yes)
			(effects
				(font
					(size 1.016 1.016)
					(thickness 0.1524)
				)
			)
		)
		(duplicate_pad_numbers_are_jumpers no)
		(fp_line
			(start -0.508 -0.9398)
			(end -0.508 0.9398)
			(stroke
				(width 0.1524)
				(type default)
			)
			(layer "F.SilkS")
		)
		(fp_line
			(start 0.508 -0.9398)
			(end -0.508 -0.9398)
			(stroke
				(width 0.1524)
				(type default)
			)
			(layer "F.SilkS")
		)
		(fp_rect
			(start -0.508 0.9398)
			(end 0.508 -0.9398)
			(stroke
				(width 0)
				(type default)
			)
			(fill no)
			(layer "F.CrtYd")
		)
		(fp_rect
			(start -0.508 0.9398)
			(end 0.508 -0.9398)
			(stroke
				(width 0)
				(type default)
			)
			(fill no)
			(layer "F.Fab")
		)
		(pad "1" smd custom
			(at 0 -0.4445)
			(size 0.1397 0.1397)
			(layers "F.Cu" "F.Mask" "F.Paste")
			(net "P0V9_EN")
			(options
				(clearance outline)
				(anchor circle)
			)
			(primitives
				(gr_poly
					(pts
						(arc
							(start -0.1778 -0.2794)
							(mid -0.249642 -0.249642)
							(end -0.2794 -0.1778)
						)
						(arc
							(start -0.2794 0.1778)
							(mid -0.249642 0.249642)
							(end -0.1778 0.2794)
						)
						(arc
							(start 0.1778 0.2794)
							(mid 0.249642 0.249642)
							(end 0.2794 0.1778)
						)
						(arc
							(start 0.2794 -0.1778)
							(mid 0.249642 -0.249642)
							(end 0.1778 -0.2794)
						)
					)
					(width 0)
					(fill yes)
				)
			)
		)
		(pad "2" smd custom
			(at 0 0.4445)
			(size 0.1397 0.1397)
			(layers "F.Cu" "F.Mask" "F.Paste")
			(net "PWRGD_P1V26_STBY")
			(options
				(clearance outline)
				(anchor circle)
			)
			(primitives
				(gr_poly
					(pts
						(arc
							(start -0.1778 -0.2794)
							(mid -0.249642 -0.249642)
							(end -0.2794 -0.1778)
						)
						(arc
							(start -0.2794 0.1778)
							(mid -0.249642 0.249642)
							(end -0.1778 0.2794)
						)
						(arc
							(start 0.1778 0.2794)
							(mid 0.249642 0.249642)
							(end 0.2794 0.1778)
						)
						(arc
							(start 0.2794 -0.1778)
							(mid 0.249642 -0.249642)
							(end 0.1778 -0.2794)
						)
					)
					(width 0)
					(fill yes)
				)
			)
		)
	)
	(footprint ""
		(layer "F.Cu")
		(at 14.478 -52.3748 180)
		(property "Reference" "R594"
			(at 0 0 180)
			(layer "F.SilkS")
			(hide yes)
			(effects
				(font
					(size 1.27 1.27)
				)
			)
		)
		(property "Value" "0R2J-2-GP"
			(at 0.064008 -3.993896 180)
			(unlocked yes)
			(layer "F.Fab")
			(hide yes)
			(effects
				(font
					(size 1.016 1.016)
					(thickness 0.1524)
				)
			)
		)
		(property "Device Type" "R402H16"
			(at 0.064008 -5.517896 180)
			(unlocked yes)
			(layer "F.Fab")
			(hide yes)
			(effects
				(font
					(size 1.016 1.016)
					(thickness 0.1524)
				)
			)
		)
		(duplicate_pad_numbers_are_jumpers no)
		(fp_line
			(start 0.508 -0.9398)
			(end -0.508 -0.9398)
			(stroke
				(width 0.1524)
				(type default)
			)
			(layer "F.SilkS")
		)
		(fp_line
			(start -0.508 -0.9398)
			(end -0.508 0.9398)
			(stroke
				(width 0.1524)
				(type default)
			)
			(layer "F.SilkS")
		)
		(fp_rect
			(start -0.508 0.9398)
			(end 0.508 -0.9398)
			(stroke
				(width 0)
				(type default)
			)
			(fill no)
			(layer "F.CrtYd")
		)
		(fp_rect
			(start -0.508 0.9398)
			(end 0.508 -0.9398)
			(stroke
				(width 0)
				(type default)
			)
			(fill no)
			(layer "F.Fab")
		)
		(pad "1" smd custom
			(at 0 -0.4445 180)
			(size 0.1397 0.1397)
			(layers "F.Cu" "F.Mask" "F.Paste")
			(net "NIC0_MDI0_P1_R")
			(options
				(clearance outline)
				(anchor circle)
			)
			(primitives
				(gr_poly
					(pts
						(arc
							(start -0.1778 -0.2794)
							(mid -0.249642 -0.249642)
							(end -0.2794 -0.1778)
						)
						(arc
							(start -0.2794 0.1778)
							(mid -0.249642 0.249642)
							(end -0.1778 0.2794)
						)
						(arc
							(start 0.1778 0.2794)
							(mid 0.249642 0.249642)
							(end 0.2794 0.1778)
						)
						(arc
							(start 0.2794 -0.1778)
							(mid 0.249642 -0.249642)
							(end 0.1778 -0.2794)
						)
					)
					(width 0)
					(fill yes)
				)
			)
		)
		(pad "2" smd custom
			(at 0 0.4445 180)
			(size 0.1397 0.1397)
			(layers "F.Cu" "F.Mask" "F.Paste")
			(net "NIC0_MDI0_P1")
			(options
				(clearance outline)
				(anchor circle)
			)
			(primitives
				(gr_poly
					(pts
						(arc
							(start -0.1778 -0.2794)
							(mid -0.249642 -0.249642)
							(end -0.2794 -0.1778)
						)
						(arc
							(start -0.2794 0.1778)
							(mid -0.249642 0.249642)
							(end -0.1778 0.2794)
						)
						(arc
							(start 0.1778 0.2794)
							(mid 0.249642 0.249642)
							(end 0.2794 0.1778)
						)
						(arc
							(start 0.2794 -0.1778)
							(mid 0.249642 -0.249642)
							(end 0.1778 -0.2794)
						)
					)
					(width 0)
					(fill yes)
				)
			)
		)
	)
	(footprint ""
		(layer "F.Cu")
		(at 45.085 -200.533 180)
		(property "Reference" "R875"
			(at 0 0 180)
			(layer "F.SilkS")
			(hide yes)
			(effects
				(font
					(size 1.27 1.27)
				)
			)
		)
		(property "Value" "10KR2F-2-GP"
			(at 0.064008 -3.993896 180)
			(unlocked yes)
			(layer "F.Fab")
			(hide yes)
			(effects
				(font
					(size 1.016 1.016)
					(thickness 0.1524)
				)
			)
		)
		(property "Device Type" "R402H16"
			(at 0.064008 -5.517896 180)
			(unlocked yes)
			(layer "F.Fab")
			(hide yes)
			(effects
				(font
					(size 1.016 1.016)
					(thickness 0.1524)
				)
			)
		)
		(duplicate_pad_numbers_are_jumpers no)
		(fp_line
			(start 0.508 -0.9398)
			(end -0.508 -0.9398)
			(stroke
				(width 0.1524)
				(type default)
			)
			(layer "F.SilkS")
		)
		(fp_line
			(start -0.508 -0.9398)
			(end -0.508 0.9398)
			(stroke
				(width 0.1524)
				(type default)
			)
			(layer "F.SilkS")
		)
		(fp_rect
			(start -0.508 0.9398)
			(end 0.508 -0.9398)
			(stroke
				(width 0)
				(type default)
			)
			(fill no)
			(layer "F.CrtYd")
		)
		(fp_rect
			(start -0.508 0.9398)
			(end 0.508 -0.9398)
			(stroke
				(width 0)
				(type default)
			)
			(fill no)
			(layer "F.Fab")
		)
		(pad "1" smd custom
			(at 0 -0.4445 180)
			(size 0.1397 0.1397)
			(layers "F.Cu" "F.Mask" "F.Paste")
			(net "P3V3_STBY")
			(options
				(clearance outline)
				(anchor circle)
			)
			(primitives
				(gr_poly
					(pts
						(arc
							(start -0.1778 -0.2794)
							(mid -0.249642 -0.249642)
							(end -0.2794 -0.1778)
						)
						(arc
							(start -0.2794 0.1778)
							(mid -0.249642 0.249642)
							(end -0.1778 0.2794)
						)
						(arc
							(start 0.1778 0.2794)
							(mid 0.249642 0.249642)
							(end 0.2794 0.1778)
						)
						(arc
							(start 0.2794 -0.1778)
							(mid 0.249642 -0.249642)
							(end 0.1778 -0.2794)
						)
					)
					(width 0)
					(fill yes)
				)
			)
		)
		(pad "2" smd custom
			(at 0 0.4445 180)
			(size 0.1397 0.1397)
			(layers "F.Cu" "F.Mask" "F.Paste")
			(net "I2C6_BUFF_EN")
			(options
				(clearance outline)
				(anchor circle)
			)
			(primitives
				(gr_poly
					(pts
						(arc
							(start -0.1778 -0.2794)
							(mid -0.249642 -0.249642)
							(end -0.2794 -0.1778)
						)
						(arc
							(start -0.2794 0.1778)
							(mid -0.249642 0.249642)
							(end -0.1778 0.2794)
						)
						(arc
							(start 0.1778 0.2794)
							(mid 0.249642 0.249642)
							(end 0.2794 0.1778)
						)
						(arc
							(start 0.2794 -0.1778)
							(mid 0.249642 -0.249642)
							(end 0.1778 -0.2794)
						)
					)
					(width 0)
					(fill yes)
				)
			)
		)
	)
	(footprint ""
		(layer "F.Cu")
		(at 20.32 -102.9208)
		(property "Reference" "R2945"
			(at 0 0 0)
			(layer "F.SilkS")
			(hide yes)
			(effects
				(font
					(size 1.27 1.27)
				)
			)
		)
		(property "Value" "4K75R2F-1-GP"
			(at 0.064008 -3.993896 0)
			(unlocked yes)
			(layer "F.Fab")
			(hide yes)
			(effects
				(font
					(size 1.016 1.016)
					(thickness 0.1524)
				)
			)
		)
		(property "Device Type" "R402H16"
			(at 0.064008 -5.517896 0)
			(unlocked yes)
			(layer "F.Fab")
			(hide yes)
			(effects
				(font
					(size 1.016 1.016)
					(thickness 0.1524)
				)
			)
		)
		(duplicate_pad_numbers_are_jumpers no)
		(fp_line
			(start -0.508 -0.9398)
			(end -0.508 0.9398)
			(stroke
				(width 0.1524)
				(type default)
			)
			(layer "F.SilkS")
		)
		(fp_line
			(start 0.508 -0.9398)
			(end -0.508 -0.9398)
			(stroke
				(width 0.1524)
				(type default)
			)
			(layer "F.SilkS")
		)
		(fp_rect
			(start -0.508 0.9398)
			(end 0.508 -0.9398)
			(stroke
				(width 0)
				(type default)
			)
			(fill no)
			(layer "F.CrtYd")
		)
		(fp_rect
			(start -0.508 0.9398)
			(end 0.508 -0.9398)
			(stroke
				(width 0)
				(type default)
			)
			(fill no)
			(layer "F.Fab")
		)
		(pad "1" smd custom
			(at 0 -0.4445)
			(size 0.1397 0.1397)
			(layers "F.Cu" "F.Mask" "F.Paste")
			(net "P3V3_STBY")
			(options
				(clearance outline)
				(anchor circle)
			)
			(primitives
				(gr_poly
					(pts
						(arc
							(start -0.1778 -0.2794)
							(mid -0.249642 -0.249642)
							(end -0.2794 -0.1778)
						)
						(arc
							(start -0.2794 0.1778)
							(mid -0.249642 0.249642)
							(end -0.1778 0.2794)
						)
						(arc
							(start 0.1778 0.2794)
							(mid 0.249642 0.249642)
							(end 0.2794 0.1778)
						)
						(arc
							(start 0.2794 -0.1778)
							(mid 0.249642 -0.249642)
							(end 0.1778 -0.2794)
						)
					)
					(width 0)
					(fill yes)
				)
			)
		)
		(pad "2" smd custom
			(at 0 0.4445)
			(size 0.1397 0.1397)
			(layers "F.Cu" "F.Mask" "F.Paste")
			(net "VREF_2V2")
			(options
				(clearance outline)
				(anchor circle)
			)
			(primitives
				(gr_poly
					(pts
						(arc
							(start -0.1778 -0.2794)
							(mid -0.249642 -0.249642)
							(end -0.2794 -0.1778)
						)
						(arc
							(start -0.2794 0.1778)
							(mid -0.249642 0.249642)
							(end -0.1778 0.2794)
						)
						(arc
							(start 0.1778 0.2794)
							(mid 0.249642 0.249642)
							(end 0.2794 0.1778)
						)
						(arc
							(start 0.2794 -0.1778)
							(mid 0.249642 -0.249642)
							(end 0.1778 -0.2794)
						)
					)
					(width 0)
					(fill yes)
				)
			)
		)
	)
	(footprint ""
		(layer "F.Cu")
		(at 50.756566 -123.430538)
		(property "Reference" "TP173"
			(at 0 0 0)
			(layer "F.SilkS")
			(hide yes)
			(effects
				(font
					(size 1.27 1.27)
				)
			)
		)
		(property "Value" "TPAD28-2-GP"
			(at -0.0127 -1.6637 0)
			(unlocked yes)
			(layer "F.Fab")
			(hide yes)
			(effects
				(font
					(size 1.016 1.016)
					(thickness 0.1524)
				)
			)
		)
		(property "Device Type" "TPAD28"
			(at -0.0127 -3.1877 0)
			(unlocked yes)
			(layer "F.Fab")
			(hide yes)
			(effects
				(font
					(size 1.016 1.016)
					(thickness 0.1524)
				)
			)
		)
		(duplicate_pad_numbers_are_jumpers no)
		(fp_poly
			(pts
				(arc
					(start 0.3556 0)
					(mid -0.3556 0)
					(end 0.3556 0)
				)
			)
			(stroke
				(width 0)
				(type default)
			)
			(fill no)
			(layer "F.CrtYd")
		)
		(fp_poly
			(pts
				(arc
					(start 0.6096 0)
					(mid -0.6096 0)
					(end 0.6096 0)
				)
			)
			(stroke
				(width 0)
				(type default)
			)
			(fill no)
			(layer "F.Fab")
		)
		(pad "1" smd circle
			(at 0 0)
			(size 0.7112 0.7112)
			(layers "F.Cu" "F.Mask" "F.Paste")
			(net "JTAG_BMC_TDI")
		)
	)
)
